FILE_TYPE = MULTI_PHYS_TABLE;

PART 'OPTICAL'

{========================================================================================}
:CLS_PN          = JEDEC_TYPE               | ALT_SYMBOLS                | DESCRIPTION                                                               | CPN_STATUS ;
{========================================================================================}
 'CL1001365A'    = 'SMC_DS_039X020_H024'    | '(SMC_DS_039X020_H024)'    | 'LED,1.0X0.5MM CHIP LED LAMP,SMD,GREEN'                                   | ''        
 'CL1001463A'    = ''                       | ''                         | 'LED CBI, 3MM, 120MIL HIGH LED CENTERLINE, GREEN'                         | ''        
 'CL1001464A'    = ''                       | ''                         | 'LED CBI, 3MM, 120MIL HIGH LED CENTERLINE, YELLOW'                        | ''        
 'CL1001465A'    = ''                       | ''                         | 'LED CBI, 3MM, 120MIL HIGH LED CENTERLINE, RED'                           | ''        
 'CL1001466A'    = ''                       | ''                         | 'LED CBI, 3MM, 120MIL HIGH LED CENTERLINE, ORANGE'                        | ''        
 'CL1001467A'    = ''                       | ''                         | 'LED CBI, 3MM, 120MIL HIGH LED CENTERLINE, RED/GREEN'                     | ''        
 'CL5000024A'    = 'TBD'                    | '(TBD)'                    | 'LED, GREEN, 20MA, 2.2V, 0603, SMT, ROHS'                                 | ''        
 'CL5002007A'    = 'SMC_DS_079X049'         | '(SMC_DS_079X049)'         | 'LED, 2.0X1.25MM CHIP LED LAMP, SMD, GREEN'                               | ''        
 'CL5003005A'    = 'SMC_DS_126X106'         | '(SMC_DS_126X106)'         | 'LED, RED, 2.1V, 20MA, 560MCD, 120 VIEW ANGLE, 624NM WAVELENGTH'          | ''        
 'CL5002056A'    = 'R2_DS157_P100'          | '(R2_DS157_P100)'          | 'LED, GREEN, 2V, 2MA, 3MM, -40 TO +85'                                    | ''        
 'CL5002057A'    = 'R2_DS157_P100'          | '(R2_DS157_P100)'          | 'LED, YELLOW, 2V, 2MA, 3MM, -40 TO +85'                                   | ''        
 'CL5003183A'    = 'SMC_DS_1608'            | '(SMC_DS_1608)'            | 'LED, GREEN, 3.3V, 20MA, 16MCD, SMD, ROHS'                                | ''        
 'CL5003179A'    = 'SMC_DS_039X020_H024'    | '(SMC_DS_039X020_H024)'    | 'LED, 1.0X0.5MM SMD CHIP LED LAMP, YELLOW, ROHS, -40~85C'                 | ''        
 'G170-00043-01'    = 'SMC_LED_0603_63X31_V1'  | '(SMC_LED_0603_63X31_V1)'  | 'LED,GREEN,525NM,3.3V,20MA,90MCD,0603'                                    | ''        
 'G170-10055-01'    = 'LED2_200X100_P100'      | '(LED2_200X100_P100)'      | 'LED, SINGLE CBI, YELLOW, 583NM, 2MM, RA, TH'                             | ''        
 'G170-10010-01'    = 'SMC_DS_063X031_H032'    | '(SMC_DS_063X031_H032)'    | 'LED,YELLOW,2V,25MA,130MCD,0603'                                          | ''        
 'G170-10011-01'    = 'SMC_DS_063X031_H032'    | '(SMC_DS_063X031_H032)'    | 'LED,GREEN,3.2V.20MA,300MCD,0603'                                         | ''        
 'G170-10061-01'    = 'LED2_200X100_P100'      | '(LED2_200X100_P100)'      | 'LED, SINGLE CBI, RED, 650NM, 2MM, RA, TH'                                | ''        
 'G170-10077-01'    = 'SMC_DS_063X031_V2_H033' | '(SMC_DS_063X031_V2_H033)' | 'LED, RED, 630NM, 1.95V, 20MA, 230MCD, 0603, SMT'                         | ''        
 'G170-10086-01'    = 'SMC_DS_098X047'         | '(SMC_DS_098X047)'         | 'LED, GREEN, 515NM, 3.3V, 20MA, 750MCD, 2.8X0.8MM, RA, SMD, ROHS'         | ''        
 'G170-10087-01'    = 'SMC_DS_079X049_H033'    | '(SMC_DS_079X049_H033)'    | 'LED, WHITE, 3.3V, 20MA, 0805, TOP-EMITTING, SMD, ROHS'                   | ''        
 'G170-10005-01'    = 'SMC_DS_063X031_V2'      | '(SMC_DS_063X031_V2)'      | 'LED,GREEN,570NM,2.1V,20MA,50MCD,0603'                                    | ''        
 'G170-10107-01'    = 'SMC_DS_063X031_V2_H033' | '(SMC_DS_063X031_V2_H033)' | 'LED,GREEN,570NM,2.1V,20MA,50MCD,0603'                                    | ''        
 'G170-10112-01'    = 'SMC_DS_063X031_V2'      | '(SMC_DS_063X031_V2)'      | 'LED,YELLOW,590NM,2V,20MA,450MCD,1.6MMX0.8MMX0.95MM SMT'                  | ''        
 'G170-10119-01'    = 'SMC_DS_063X031_V2_H033' | '(SMC_DS_063X031_V2_H033)' | 'LED,SUPER BRIGHT YELLOW,590NM,2V,10UA,150MCD/20MA,1.6X0.8MM,SMT'         | ''        
 'G170-10136-01'    = 'SMC_DS_039X020_H024'    | '(SMC_DS_039X020_H024)'    | 'LED,AMBER,590NM,2V,20MA,150MCD,1MMX0.5MM,SMT'                            | ''        
 'G170-10137-01'    = 'SMC_DS_063X031_V3'      | '(SMC_DS_063X031_V3)'      | 'LED,GREEN,568NM,2.2V,20MA,12MCD,0603'                                    | ''        
 'G170-10139-01'    = 'LED2_170X481_P100'      | '(LED2_170X481_P100_CST)'  | 'LED,GREEN,568NM,2.2V,10MA,25MCD,4.32X9.02X9.65,PTH'                      | ''        
 'G170-10143-01'    = 'SMC_DS_063X031_V4'      | '(SMC_DS_063X031_V4)'      | 'LED,GREEN,UPPER LIGHT,571NM,5V,30MA,35MCD,SMT'                           | ''        
 'G170-10148-01'    = 'SMC_DS_063X031_V2_H033' | '(SMC_DS_063X031_V2_H033)' | 'LED,BLUE,465NM,3.3V,20MA,100MCD,1.6MMX0.8MM,SMT'                         | ''        
 'G170-10150-01'    = 'LED2_170X481_P100'      | '(LED2_170X481_P100)'      | 'LED,GREEN,525NM,3.3V,20MA,1300MCD,4.32X9.02X9.65,PTH'                    | ''        
 'G170-10155-01'    = 'SMC_DS_063X047'         | '(SMC_DS_063X047)'         | 'LED,GREEN,570NM,2.1V@20MA,50MCD,1.6X0.6MM,RA,SMD'                        | ''        
 'G170-10156-01'    = 'SMC_DS_063X047'         | '(SMC_DS_063X047)'         | 'LED,RED,630NM,1.95@20MA,220MCD,1.6X0.6MM,RA,SMD'                         | ''        
 'G170-10115-01'    = 'SMC_DS_063X047'         | '(SMC_DS_063X047)'         | 'LED,YELLOW,590NM,2V@20MA,150MCD,1.6X0.6MM,RA,SMD'                        | ''        
 'G170-10142-01'    = 'SMC_DS_071X039'         | '(SMC_DS_071X039)'         | 'LED,GREEN,571NM,5V,30MA,MAX 28 MCD,SMT'                                  | ''        
 'A170-00002-EM'    = 'SMC_DS_118X110_V1'      | '(SMC_DS_118X110_V1)'      | 'LED,GREEN,570NM,400MCD,2.1V,3.0MM X 2.0MM,RA,SMT'                        | ''        
 'G170-10169-01'    = 'SMC_DS_063X031_V2_H018' | '(SMC_DS_063X031_V2_H018)' | 'LED,GREEN,568NM,2.2V,20MA,1.6MMX0.8MM,SMT'                               | ''        
 'G170-00028-01'    = 'SMC_LED_0603_63X31_V1'  | '(SMC_LED_0603_63X31_V1)'  | 'LED,AMBER,590NM,2.0V,20MA,63MCD,0603'                                    | 'NFND'    
 'G170-10170-01'    = 'LED2_157X350_P100'      | '(LED2_157X350_P100)'      | 'LED,RIGHT ANGLE HOUSING LED,GREEN,568NM,2.2V,20MA,6MCD,TH'               | ''        
 'G170-10178-01'    = 'SMC_DS_063X031_V6'      | '(SMC_DS_063X031_V6)'      | 'LED,RED,621NM,1.7V,20MA,57MCD,1.6MMX0.8MM,0.8MM HEIGHT,0603'             | ''        
 'G170-10179-01'    = 'SMC_DS_063X031_V6'      | '(SMC_DS_063X031_V6)'      | 'LED,YELLOW,586NM,1.7V,20MA,112MCD,1.6MMX0.8MM,0.8MM HEIGHT,0603'         | ''        
 'G170-10181-01'    = 'SMC_DS_063X031_V6'      | '(SMC_DS_063X031_V6)'      | 'LED,YELLOW GREEN,571.5NM,1.75V,20MA,57MCD,1.6MMX0.8MM,0.8MM HEIGHT,0603' | ''        
 'G170-10182-01'    = 'SMC_DS_063X031_H018'    | '(SMC_DS_063X031_H018)'    | 'LED,BLUE,470NM,2.7V,20MA,140MCD,1.6MMX0.8MM,0.4MM HEIGHT,0603'           | ''        
 'G170-00029-01'    = 'SMC_LED_0603_63X31_V1'  | '(SMC_LED_0603_63X31_V1)'  | 'LED,BLUE,468NM,3.3V,20MA,22MCD,0603'                                     | 'NFND'    
 'G170-10075-01'    = 'SMC_DS_063X031_V2_H033' | '(SMC_DS_063X031_V2_H033)' | 'LED, GREEN, 525NM, 3.3V, 20MA, 450MCD, 0603, SMT'                        | ''        
 'G170-10166-01'    = 'LED2_C228_P100_V1'      | '(LED2_C228_P100_V1)'      | 'LED,GREEN,562-575NM,2.0V,2MA,2MCD,DIA.TH'                                | ''        
 'G170-10116-01'    = 'SMC_DS_063X047'         | '(SMC_DS_063X047)'         | 'LED,BLUE,465NM,3.3V@20MA,150MCD,1.6X0.6MM,RA,SMD'                        | ''        
 'G170-10114-01'    = 'SMC_DS_063X047'         | '(SMC_DS_063X047)'         | 'LED,GREEN,525NM,3.3V@20MA,400MCD,1.6X0.6MM,RA,SMD'                       | ''        
 'G170-10201-01'    = 'SMC_DS_063X047'         | '(SMC_DS_063X047)'         | 'LED,ORANGE,605NM,2.1V,20MA,250MCD,1.6X1.2X0.6MM,R/A SMT'                 | ''        
 'G170-10196-01'    = 'SMC_DS_063X031_H028'    | '(SMC_DS_063X031_H028)'    | 'LED,AMBER,591NM,2.0V,20MA,80MCD,0603'                                    | ''        
 'G170-10207-01'    = 'SMC_DS_079X049_V1'      | '(SMC_DS_079X049_V1)'      | 'LED,GREEN,515NM,3.3V,20MA,400MCD,2.0MMX1.25MM,SMT'                       | ''        
 'G170-10208-01'    = 'SMC_DS_063X031_V2_H018' | '(SMC_DS_063X031_V2_H018)' | 'LED,GREEN,515NM,3.3V,25MA,550MCD,1.6MMX0.8MM,SMT'                        | ''        
 'A170-20021-DL'    = 'SMC_DS_039X020_V1'      | '(SMC_DS_039X020_V1)'      | 'LED, INGAN BLUE, 465~475NM, 2.8~3.8V, 1.0MM X 0.5MM X 0.35MM'            | ''        
 'A170-20011-DL'    = 'SMC_DS_039X020_V1'      | '(SMC_DS_039X020_V1)'      | 'LED, INGAN BLUE, 470NM, 2.9V, 1.0MM X 0.5MM X 0.35MM'                    | ''        
 'G170-10025-01'    = 'SMC_DS_063X031_H020'    | '(SMC_DS_063X031_H020)'    | 'LED,GREEN,565NM,2.6V,20MA,SMD0603'                                       | ''        
 'G170-10220-01'    = 'SMC_DS_118X110_V1'      | '(SMC_DS_118X110_V1)'      | 'LED,GREEN,525NM,3.3V,25MA,5800MCD,3.0MM X 2.0MM,RA,SMT'                  | ''        
 'G170-10004-01'    = 'SMC_DS_063X031_V2'      | '(SMC_DS_063X031_V2)'      | 'LED,BLUE,465NM,3.3V,20MA,150MCD,0603'                                    | ''        
 'G170-10216-01'    = 'SMC_DS_063X031_V4'      | '(SMC_DS_063X031_V4)'      | 'LED,YELLOW GREEN,568NM,2.2V,20MA,8.2MCD,VERTICAL,1.6X0.8MM,SMT'          | ''        
 'G171-10006-01'    = 'SMC_DS_039X020_H024'    | '(SMC_DS_039X020_H024)'    | 'LED,GREEN,2.1V,20MA,50MCD,1.0MMX0.5MM,120DEG,SMT'                        | ''        
 'G170-10215-01'    = 'SMC_DS_063X031_V4'      | '(SMC_DS_063X031_V4)'      | 'LED,GREEN,574NM,5V,30MA,MAX57.0MCD,130DEG,1.6X0.8MM,SMT'                 | ''        
 'G170-10225-01'    = 'SMC_DS_079X049_V4'      | '(SMC_DS_079X049_V4)'      | 'LED,GREEN LED 527NM,3V,20MA,140MCD,0805,SMD,VT'                          | ''        
 'G170-10224-01'    = 'SMC_DS_079X049_V4'      | '(SMC_DS_079X049_V4)'      | 'LED,BLUE LED 470NM,2.9V,20MA,0805,SMD,VT'                                | ''        
 'G170-10223-01'    = 'SMC_DS_079X049_V4'      | '(SMC_DS_079X049_V4)'      | 'LED,YELLOW LED 590NM,2V,20MA,0805,SMD,VT'                                | ''        
 'G170-10228-01'    = 'SMC_DS_063X031_V4_H018' | '(SMC_DS_063X031_V4_H018)' | 'LED,BRILIANT RED,632NM,2V,25MA,112MCD,1.6X0.8MM'                         | ''        
 'A170-00029-IB'    = 'SMC_LED_0603_63X31_V1'  | '(SMC_LED_0603_63X31_V1)'  | 'LED,BLUE,469NM,3.3V,20MA,45-112.5MCD,-30-85C,1.7*0.9*0.9MM,SMT'          | ''    
 'G170-00029-02'    = 'smc_led_0603_63x31_v1_h035'| '(smc_led_0603_63x31_v1_h035)'| 'LED,BLUE,469NM,3.3V,20MA,45-112.5MCD,-30-85C,1.7*0.9*0.9MM,SMT'    | ''    

END_PART

END.

